FILE_TYPE=LIBRARY_PARTS;
primitive 'SC1U16V3KX-2GP_SMD-BCG';
  pin
    '1':
      PIN_NUMBER='(1)';
      PIN_TYPE='ANALOG';
      NO_LOAD_CHECK='Both';
      NO_IO_CHECK='Both';
      NO_ASSERT_CHECK='TRUE';
      NO_DIR_CHECK='TRUE';
      ALLOW_CONNECT='TRUE';
    '2':
      PIN_NUMBER='(2)';
      PIN_TYPE='ANALOG';
      NO_LOAD_CHECK='Both';
      NO_IO_CHECK='Both';
      NO_ASSERT_CHECK='TRUE';
      NO_DIR_CHECK='TRUE';
      ALLOW_CONNECT='TRUE';
  end_pin;
  body
    PART_NAME='SC1U16V3KX-2GP';
    BODY_NAME='SC1U16V3KX-2GP';
    PHYS_DES_PREFIX='C';
    CLASS='DISCRETE';
  end_body;
end_primitive;

END.
